(kicad_pcb
	(version 20260206)
	(generator "pcbnew")
	(generator_version "10.0")
	(general
		(thickness 1.6)
		(legacy_teardrops no)
	)
	(paper "A4")
	(title_block
		(title "04192023_DAF0TMB3IC0_F0TG_MB_C_brd_V02_OCP.brd")
		(comment 1 "Grand Teton / footprints 7264-7270 of 8354")
	)
	(layers
		(0 "F.Cu" signal "TOP")
		(4 "In1.Cu" signal "GND")
		(6 "In2.Cu" signal "IN1")
		(8 "In3.Cu" signal "GND1")
		(10 "In4.Cu" signal "IN2")
		(12 "In5.Cu" signal "GND2")
		(14 "In6.Cu" signal "IN3")
		(16 "In7.Cu" signal "GND3")
		(18 "In8.Cu" signal "VCC")
		(20 "In9.Cu" signal "VCC1")
		(22 "In10.Cu" signal "GND4")
		(24 "In11.Cu" signal "IN4")
		(26 "In12.Cu" signal "GND5")
		(28 "In13.Cu" signal "IN5")
		(30 "In14.Cu" signal "GND6")
		(32 "In15.Cu" signal "IN6")
		(34 "In16.Cu" signal "GND7")
		(2 "B.Cu" signal "BOTTOM")
		(9 "F.Adhes" user "F.Adhesive")
		(11 "B.Adhes" user "B.Adhesive")
		(13 "F.Paste" user "Package Geometry/Pastemask Top")
		(15 "B.Paste" user "Package Geometry/Pastemask Bottom")
		(5 "F.SilkS" user "Ref Des/Silkscreen Top")
		(7 "B.SilkS" user "Ref Des/Silkscreen Bottom")
		(1 "F.Mask" user "Board Geometry/Soldermask Top")
		(3 "B.Mask" user "Board Geometry/Soldermask Bottom")
		(17 "Dwgs.User" user "User.Drawings")
		(19 "Cmts.User" user "User.Comments")
		(21 "Eco1.User" user "User.Eco1")
		(23 "Eco2.User" user "User.Eco2")
		(25 "Edge.Cuts" user "Board Geometry/Outline")
		(27 "Margin" user)
		(31 "F.CrtYd" user "Package Geometry/Place Bound Top")
		(29 "B.CrtYd" user "Package Geometry/Place Bound Bottom")
		(35 "F.Fab" user "Ref Des/Assembly Top")
		(33 "B.Fab" user "Ref Des/Assembly Bottom")
	)
	(footprint ""
		(layer "B.Cu")
		(at 169.2148 -421.277796 -90)
		(property "Reference" "R1463"
			(at 0 0 90)
			(layer "B.SilkS")
			(hide yes)
			(effects
				(font
					(size 1.27 1.27)
				)
				(justify mirror)
			)
		)
		(property "Value" ""
			(at 0 0 90)
			(layer "B.Fab")
			(effects
				(font
					(size 1.27 1.27)
				)
				(justify mirror)
			)
		)
		(duplicate_pad_numbers_are_jumpers no)
		(fp_line
			(start -0.32512 0.175006)
			(end 0.32512 0.175006)
			(stroke
				(width 0.1)
				(type default)
			)
			(layer "B.Fab")
		)
		(fp_line
			(start 0.32512 0.175006)
			(end 0.32512 -0.175006)
			(stroke
				(width 0.1)
				(type default)
			)
			(layer "B.Fab")
		)
		(fp_line
			(start -0.32512 -0.175006)
			(end -0.32512 0.175006)
			(stroke
				(width 0.1)
				(type default)
			)
			(layer "B.Fab")
		)
		(fp_line
			(start 0.32512 -0.175006)
			(end -0.32512 -0.175006)
			(stroke
				(width 0.1)
				(type default)
			)
			(layer "B.Fab")
		)
		(pad "1" smd rect
			(at 0.2667 0 90)
			(size 0.3048 0.381)
			(layers "B.Cu" "B.Mask" "B.Paste")
			(net "P1V8_CPU1_RT_1D")
		)
		(pad "2" smd rect
			(at -0.2667 0 270)
			(size 0.3048 0.381)
			(layers "B.Cu" "B.Mask" "B.Paste")
			(net "SMB_RT_CPU1_P3_ROM_MUX_1D_SCL")
		)
	)
	(footprint ""
		(layer "B.Cu")
		(at 100.478844 -259.73024 180)
		(property "Reference" "C2103"
			(at 0 0 0)
			(layer "B.SilkS")
			(hide yes)
			(effects
				(font
					(size 1.27 1.27)
				)
				(justify mirror)
			)
		)
		(property "Value" ""
			(at 0 0 0)
			(layer "B.Fab")
			(effects
				(font
					(size 1.27 1.27)
				)
				(justify mirror)
			)
		)
		(duplicate_pad_numbers_are_jumpers no)
		(fp_line
			(start 0.7874 0.4064)
			(end 0.7874 -0.4064)
			(stroke
				(width 0.1524)
				(type default)
			)
			(layer "B.SilkS")
		)
		(fp_line
			(start 0.7874 -0.4064)
			(end -0.7874 -0.4064)
			(stroke
				(width 0.1524)
				(type default)
			)
			(layer "B.SilkS")
		)
		(fp_line
			(start -0.7874 0.4064)
			(end 0.7874 0.4064)
			(stroke
				(width 0.1524)
				(type default)
			)
			(layer "B.SilkS")
		)
		(fp_line
			(start -0.7874 -0.4064)
			(end -0.7874 0.4064)
			(stroke
				(width 0.1524)
				(type default)
			)
			(layer "B.SilkS")
		)
		(fp_line
			(start 0.67945 0.3048)
			(end 0.67945 -0.305054)
			(stroke
				(width 0.1)
				(type default)
			)
			(layer "B.Fab")
		)
		(fp_line
			(start 0.67945 -0.305054)
			(end 0.12065 -0.305054)
			(stroke
				(width 0.1)
				(type default)
			)
			(layer "B.Fab")
		)
		(fp_line
			(start 0.12065 0.3048)
			(end 0.67945 0.3048)
			(stroke
				(width 0.1)
				(type default)
			)
			(layer "B.Fab")
		)
		(fp_line
			(start 0.12065 0.2794)
			(end 0.12065 0.3048)
			(stroke
				(width 0.1)
				(type default)
			)
			(layer "B.Fab")
		)
		(fp_line
			(start 0.12065 -0.2794)
			(end -0.12065 -0.2794)
			(stroke
				(width 0.1)
				(type default)
			)
			(layer "B.Fab")
		)
		(fp_line
			(start 0.12065 -0.305054)
			(end 0.12065 -0.2794)
			(stroke
				(width 0.1)
				(type default)
			)
			(layer "B.Fab")
		)
		(fp_line
			(start -0.120396 0.3048)
			(end -0.120396 0.2794)
			(stroke
				(width 0.1)
				(type default)
			)
			(layer "B.Fab")
		)
		(fp_line
			(start -0.120396 0.2794)
			(end 0.12065 0.2794)
			(stroke
				(width 0.1)
				(type default)
			)
			(layer "B.Fab")
		)
		(fp_line
			(start -0.12065 -0.2794)
			(end -0.12065 -0.3048)
			(stroke
				(width 0.1)
				(type default)
			)
			(layer "B.Fab")
		)
		(fp_line
			(start -0.12065 -0.3048)
			(end -0.67945 -0.3048)
			(stroke
				(width 0.1)
				(type default)
			)
			(layer "B.Fab")
		)
		(fp_line
			(start -0.67945 0.3048)
			(end -0.120396 0.3048)
			(stroke
				(width 0.1)
				(type default)
			)
			(layer "B.Fab")
		)
		(fp_line
			(start -0.67945 -0.3048)
			(end -0.67945 0.3048)
			(stroke
				(width 0.1)
				(type default)
			)
			(layer "B.Fab")
		)
		(pad "1" smd circle
			(at 0.40005 0)
			(size 0 0)
			(layers "B.Cu" "B.Mask" "B.Paste")
			(net "PVDDIO_P1")
		)
		(pad "2" smd circle
			(at -0.40005 0)
			(size 0 0)
			(layers "B.Cu" "B.Mask" "B.Paste")
			(net "GND")
		)
	)
	(footprint ""
		(layer "B.Cu")
		(at 361.316016 -256.012188 -90)
		(property "Reference" "C2580"
			(at 0 0 90)
			(layer "B.SilkS")
			(hide yes)
			(effects
				(font
					(size 1.27 1.27)
				)
				(justify mirror)
			)
		)
		(property "Value" ""
			(at 0 0 90)
			(layer "B.Fab")
			(effects
				(font
					(size 1.27 1.27)
				)
				(justify mirror)
			)
		)
		(duplicate_pad_numbers_are_jumpers no)
		(fp_line
			(start -0.7874 0.4064)
			(end 0.7874 0.4064)
			(stroke
				(width 0.1524)
				(type default)
			)
			(layer "B.SilkS")
		)
		(fp_line
			(start 0.7874 0.4064)
			(end 0.7874 -0.4064)
			(stroke
				(width 0.1524)
				(type default)
			)
			(layer "B.SilkS")
		)
		(fp_line
			(start -0.7874 -0.4064)
			(end -0.7874 0.4064)
			(stroke
				(width 0.1524)
				(type default)
			)
			(layer "B.SilkS")
		)
		(fp_line
			(start 0.7874 -0.4064)
			(end -0.7874 -0.4064)
			(stroke
				(width 0.1524)
				(type default)
			)
			(layer "B.SilkS")
		)
		(fp_line
			(start -0.67945 0.3048)
			(end -0.120396 0.3048)
			(stroke
				(width 0.1)
				(type default)
			)
			(layer "B.Fab")
		)
		(fp_line
			(start -0.120396 0.3048)
			(end -0.120396 0.2794)
			(stroke
				(width 0.1)
				(type default)
			)
			(layer "B.Fab")
		)
		(fp_line
			(start 0.12065 0.3048)
			(end 0.67945 0.3048)
			(stroke
				(width 0.1)
				(type default)
			)
			(layer "B.Fab")
		)
		(fp_line
			(start 0.67945 0.3048)
			(end 0.67945 -0.305054)
			(stroke
				(width 0.1)
				(type default)
			)
			(layer "B.Fab")
		)
		(fp_line
			(start -0.120396 0.2794)
			(end 0.12065 0.2794)
			(stroke
				(width 0.1)
				(type default)
			)
			(layer "B.Fab")
		)
		(fp_line
			(start 0.12065 0.2794)
			(end 0.12065 0.3048)
			(stroke
				(width 0.1)
				(type default)
			)
			(layer "B.Fab")
		)
		(fp_line
			(start -0.12065 -0.2794)
			(end -0.12065 -0.3048)
			(stroke
				(width 0.1)
				(type default)
			)
			(layer "B.Fab")
		)
		(fp_line
			(start 0.12065 -0.2794)
			(end -0.12065 -0.2794)
			(stroke
				(width 0.1)
				(type default)
			)
			(layer "B.Fab")
		)
		(fp_line
			(start -0.67945 -0.3048)
			(end -0.67945 0.3048)
			(stroke
				(width 0.1)
				(type default)
			)
			(layer "B.Fab")
		)
		(fp_line
			(start -0.12065 -0.3048)
			(end -0.67945 -0.3048)
			(stroke
				(width 0.1)
				(type default)
			)
			(layer "B.Fab")
		)
		(fp_line
			(start 0.12065 -0.305054)
			(end 0.12065 -0.2794)
			(stroke
				(width 0.1)
				(type default)
			)
			(layer "B.Fab")
		)
		(fp_line
			(start 0.67945 -0.305054)
			(end 0.12065 -0.305054)
			(stroke
				(width 0.1)
				(type default)
			)
			(layer "B.Fab")
		)
		(pad "1" smd circle
			(at 0.40005 0 90)
			(size 0 0)
			(layers "B.Cu" "B.Mask" "B.Paste")
			(net "PVDDCR_SOC_P0")
		)
		(pad "2" smd circle
			(at -0.40005 0 90)
			(size 0 0)
			(layers "B.Cu" "B.Mask" "B.Paste")
			(net "GND")
		)
	)
	(footprint ""
		(layer "B.Cu")
		(at 172.456094 -417.078668)
		(property "Reference" "R2916"
			(at 0 0 0)
			(layer "B.SilkS")
			(hide yes)
			(effects
				(font
					(size 1.27 1.27)
				)
				(justify mirror)
			)
		)
		(property "Value" ""
			(at 0 0 0)
			(layer "B.Fab")
			(effects
				(font
					(size 1.27 1.27)
				)
				(justify mirror)
			)
		)
		(duplicate_pad_numbers_are_jumpers no)
		(fp_line
			(start -0.7874 -0.4064)
			(end -0.7874 0.4064)
			(stroke
				(width 0.1524)
				(type default)
			)
			(layer "B.SilkS")
		)
		(fp_line
			(start -0.7874 0.4064)
			(end 0.7874 0.4064)
			(stroke
				(width 0.1524)
				(type default)
			)
			(layer "B.SilkS")
		)
		(fp_line
			(start 0.7874 -0.4064)
			(end -0.7874 -0.4064)
			(stroke
				(width 0.1524)
				(type default)
			)
			(layer "B.SilkS")
		)
		(fp_line
			(start 0.7874 0.4064)
			(end 0.7874 -0.4064)
			(stroke
				(width 0.1524)
				(type default)
			)
			(layer "B.SilkS")
		)
		(fp_line
			(start -0.67945 -0.3048)
			(end -0.67945 0.3048)
			(stroke
				(width 0.1)
				(type default)
			)
			(layer "B.Fab")
		)
		(fp_line
			(start -0.67945 0.3048)
			(end -0.120396 0.3048)
			(stroke
				(width 0.1)
				(type default)
			)
			(layer "B.Fab")
		)
		(fp_line
			(start -0.12065 -0.3048)
			(end -0.67945 -0.3048)
			(stroke
				(width 0.1)
				(type default)
			)
			(layer "B.Fab")
		)
		(fp_line
			(start -0.12065 -0.2794)
			(end -0.12065 -0.3048)
			(stroke
				(width 0.1)
				(type default)
			)
			(layer "B.Fab")
		)
		(fp_line
			(start -0.120396 0.2794)
			(end 0.12065 0.2794)
			(stroke
				(width 0.1)
				(type default)
			)
			(layer "B.Fab")
		)
		(fp_line
			(start -0.120396 0.3048)
			(end -0.120396 0.2794)
			(stroke
				(width 0.1)
				(type default)
			)
			(layer "B.Fab")
		)
		(fp_line
			(start 0.12065 -0.305054)
			(end 0.12065 -0.2794)
			(stroke
				(width 0.1)
				(type default)
			)
			(layer "B.Fab")
		)
		(fp_line
			(start 0.12065 -0.2794)
			(end -0.12065 -0.2794)
			(stroke
				(width 0.1)
				(type default)
			)
			(layer "B.Fab")
		)
		(fp_line
			(start 0.12065 0.2794)
			(end 0.12065 0.3048)
			(stroke
				(width 0.1)
				(type default)
			)
			(layer "B.Fab")
		)
		(fp_line
			(start 0.12065 0.3048)
			(end 0.67945 0.3048)
			(stroke
				(width 0.1)
				(type default)
			)
			(layer "B.Fab")
		)
		(fp_line
			(start 0.67945 -0.305054)
			(end 0.12065 -0.305054)
			(stroke
				(width 0.1)
				(type default)
			)
			(layer "B.Fab")
		)
		(fp_line
			(start 0.67945 0.3048)
			(end 0.67945 -0.305054)
			(stroke
				(width 0.1)
				(type default)
			)
			(layer "B.Fab")
		)
		(pad "1" smd circle
			(at 0.40005 0 180)
			(size 0 0)
			(layers "B.Cu" "B.Mask" "B.Paste")
			(net "RST_SWB_BIC_R_N")
		)
		(pad "2" smd circle
			(at -0.40005 0 180)
			(size 0 0)
			(layers "B.Cu" "B.Mask" "B.Paste")
			(net "GND")
		)
	)
	(footprint ""
		(layer "B.Cu")
		(at 197.269608 -125.817376 180)
		(property "Reference" "R6113"
			(at 0 0 0)
			(layer "B.SilkS")
			(hide yes)
			(effects
				(font
					(size 1.27 1.27)
				)
				(justify mirror)
			)
		)
		(property "Value" ""
			(at 0 0 0)
			(layer "B.Fab")
			(effects
				(font
					(size 1.27 1.27)
				)
				(justify mirror)
			)
		)
		(duplicate_pad_numbers_are_jumpers no)
		(fp_line
			(start 0.7874 0.4064)
			(end 0.7874 -0.4064)
			(stroke
				(width 0.1524)
				(type default)
			)
			(layer "B.SilkS")
		)
		(fp_line
			(start 0.7874 -0.4064)
			(end -0.7874 -0.4064)
			(stroke
				(width 0.1524)
				(type default)
			)
			(layer "B.SilkS")
		)
		(fp_line
			(start -0.7874 0.4064)
			(end 0.7874 0.4064)
			(stroke
				(width 0.1524)
				(type default)
			)
			(layer "B.SilkS")
		)
		(fp_line
			(start -0.7874 -0.4064)
			(end -0.7874 0.4064)
			(stroke
				(width 0.1524)
				(type default)
			)
			(layer "B.SilkS")
		)
		(fp_line
			(start 0.67945 0.3048)
			(end 0.67945 -0.305054)
			(stroke
				(width 0.1)
				(type default)
			)
			(layer "B.Fab")
		)
		(fp_line
			(start 0.67945 -0.305054)
			(end 0.12065 -0.305054)
			(stroke
				(width 0.1)
				(type default)
			)
			(layer "B.Fab")
		)
		(fp_line
			(start 0.12065 0.3048)
			(end 0.67945 0.3048)
			(stroke
				(width 0.1)
				(type default)
			)
			(layer "B.Fab")
		)
		(fp_line
			(start 0.12065 0.2794)
			(end 0.12065 0.3048)
			(stroke
				(width 0.1)
				(type default)
			)
			(layer "B.Fab")
		)
		(fp_line
			(start 0.12065 -0.2794)
			(end -0.12065 -0.2794)
			(stroke
				(width 0.1)
				(type default)
			)
			(layer "B.Fab")
		)
		(fp_line
			(start 0.12065 -0.305054)
			(end 0.12065 -0.2794)
			(stroke
				(width 0.1)
				(type default)
			)
			(layer "B.Fab")
		)
		(fp_line
			(start -0.120396 0.3048)
			(end -0.120396 0.2794)
			(stroke
				(width 0.1)
				(type default)
			)
			(layer "B.Fab")
		)
		(fp_line
			(start -0.120396 0.2794)
			(end 0.12065 0.2794)
			(stroke
				(width 0.1)
				(type default)
			)
			(layer "B.Fab")
		)
		(fp_line
			(start -0.12065 -0.2794)
			(end -0.12065 -0.3048)
			(stroke
				(width 0.1)
				(type default)
			)
			(layer "B.Fab")
		)
		(fp_line
			(start -0.12065 -0.3048)
			(end -0.67945 -0.3048)
			(stroke
				(width 0.1)
				(type default)
			)
			(layer "B.Fab")
		)
		(fp_line
			(start -0.67945 0.3048)
			(end -0.120396 0.3048)
			(stroke
				(width 0.1)
				(type default)
			)
			(layer "B.Fab")
		)
		(fp_line
			(start -0.67945 -0.3048)
			(end -0.67945 0.3048)
			(stroke
				(width 0.1)
				(type default)
			)
			(layer "B.Fab")
		)
		(pad "1" smd circle
			(at 0.40005 0)
			(size 0 0)
			(layers "B.Cu" "B.Mask" "B.Paste")
			(net "RST_PERST_CPU1_SWB_N")
		)
		(pad "2" smd circle
			(at -0.40005 0)
			(size 0 0)
			(layers "B.Cu" "B.Mask" "B.Paste")
			(net "RST_PERST_CPU1_SWB_R_N")
		)
	)
	(footprint ""
		(layer "B.Cu")
		(at 15.042388 -134.16407)
		(property "Reference" "C97"
			(at 0 0 0)
			(layer "B.SilkS")
			(hide yes)
			(effects
				(font
					(size 1.27 1.27)
				)
				(justify mirror)
			)
		)
		(property "Value" ""
			(at 0 0 0)
			(layer "B.Fab")
			(effects
				(font
					(size 1.27 1.27)
				)
				(justify mirror)
			)
		)
		(duplicate_pad_numbers_are_jumpers no)
		(fp_line
			(start -0.7874 -0.4064)
			(end -0.7874 0.4064)
			(stroke
				(width 0.1524)
				(type default)
			)
			(layer "B.SilkS")
		)
		(fp_line
			(start -0.7874 0.4064)
			(end 0.7874 0.4064)
			(stroke
				(width 0.1524)
				(type default)
			)
			(layer "B.SilkS")
		)
		(fp_line
			(start 0.7874 -0.4064)
			(end -0.7874 -0.4064)
			(stroke
				(width 0.1524)
				(type default)
			)
			(layer "B.SilkS")
		)
		(fp_line
			(start 0.7874 0.4064)
			(end 0.7874 -0.4064)
			(stroke
				(width 0.1524)
				(type default)
			)
			(layer "B.SilkS")
		)
		(fp_line
			(start -0.67945 -0.3048)
			(end -0.67945 0.3048)
			(stroke
				(width 0.1)
				(type default)
			)
			(layer "B.Fab")
		)
		(fp_line
			(start -0.67945 0.3048)
			(end -0.120396 0.3048)
			(stroke
				(width 0.1)
				(type default)
			)
			(layer "B.Fab")
		)
		(fp_line
			(start -0.12065 -0.3048)
			(end -0.67945 -0.3048)
			(stroke
				(width 0.1)
				(type default)
			)
			(layer "B.Fab")
		)
		(fp_line
			(start -0.12065 -0.2794)
			(end -0.12065 -0.3048)
			(stroke
				(width 0.1)
				(type default)
			)
			(layer "B.Fab")
		)
		(fp_line
			(start -0.120396 0.2794)
			(end 0.12065 0.2794)
			(stroke
				(width 0.1)
				(type default)
			)
			(layer "B.Fab")
		)
		(fp_line
			(start -0.120396 0.3048)
			(end -0.120396 0.2794)
			(stroke
				(width 0.1)
				(type default)
			)
			(layer "B.Fab")
		)
		(fp_line
			(start 0.12065 -0.305054)
			(end 0.12065 -0.2794)
			(stroke
				(width 0.1)
				(type default)
			)
			(layer "B.Fab")
		)
		(fp_line
			(start 0.12065 -0.2794)
			(end -0.12065 -0.2794)
			(stroke
				(width 0.1)
				(type default)
			)
			(layer "B.Fab")
		)
		(fp_line
			(start 0.12065 0.2794)
			(end 0.12065 0.3048)
			(stroke
				(width 0.1)
				(type default)
			)
			(layer "B.Fab")
		)
		(fp_line
			(start 0.12065 0.3048)
			(end 0.67945 0.3048)
			(stroke
				(width 0.1)
				(type default)
			)
			(layer "B.Fab")
		)
		(fp_line
			(start 0.67945 -0.305054)
			(end 0.12065 -0.305054)
			(stroke
				(width 0.1)
				(type default)
			)
			(layer "B.Fab")
		)
		(fp_line
			(start 0.67945 0.3048)
			(end 0.67945 -0.305054)
			(stroke
				(width 0.1)
				(type default)
			)
			(layer "B.Fab")
		)
		(pad "1" smd circle
			(at 0.40005 0 180)
			(size 0 0)
			(layers "B.Cu" "B.Mask" "B.Paste")
			(net "VFG_3P3A_CLK_GEN")
		)
		(pad "2" smd circle
			(at -0.40005 0 180)
			(size 0 0)
			(layers "B.Cu" "B.Mask" "B.Paste")
			(net "GND")
		)
	)
	(footprint ""
		(layer "B.Cu")
		(at 365.773208 -267.52931)
		(property "Reference" "C2255"
			(at 0 0 0)
			(layer "B.SilkS")
			(hide yes)
			(effects
				(font
					(size 1.27 1.27)
				)
				(justify mirror)
			)
		)
		(property "Value" ""
			(at 0 0 0)
			(layer "B.Fab")
			(effects
				(font
					(size 1.27 1.27)
				)
				(justify mirror)
			)
		)
		(duplicate_pad_numbers_are_jumpers no)
		(fp_line
			(start -0.7874 -0.4064)
			(end -0.7874 0.4064)
			(stroke
				(width 0.1524)
				(type default)
			)
			(layer "B.SilkS")
		)
		(fp_line
			(start -0.7874 0.4064)
			(end 0.7874 0.4064)
			(stroke
				(width 0.1524)
				(type default)
			)
			(layer "B.SilkS")
		)
		(fp_line
			(start 0.7874 -0.4064)
			(end -0.7874 -0.4064)
			(stroke
				(width 0.1524)
				(type default)
			)
			(layer "B.SilkS")
		)
		(fp_line
			(start 0.7874 0.4064)
			(end 0.7874 -0.4064)
			(stroke
				(width 0.1524)
				(type default)
			)
			(layer "B.SilkS")
		)
		(fp_line
			(start -0.67945 -0.3048)
			(end -0.67945 0.3048)
			(stroke
				(width 0.1)
				(type default)
			)
			(layer "B.Fab")
		)
		(fp_line
			(start -0.67945 0.3048)
			(end -0.120396 0.3048)
			(stroke
				(width 0.1)
				(type default)
			)
			(layer "B.Fab")
		)
		(fp_line
			(start -0.12065 -0.3048)
			(end -0.67945 -0.3048)
			(stroke
				(width 0.1)
				(type default)
			)
			(layer "B.Fab")
		)
		(fp_line
			(start -0.12065 -0.2794)
			(end -0.12065 -0.3048)
			(stroke
				(width 0.1)
				(type default)
			)
			(layer "B.Fab")
		)
		(fp_line
			(start -0.120396 0.2794)
			(end 0.12065 0.2794)
			(stroke
				(width 0.1)
				(type default)
			)
			(layer "B.Fab")
		)
		(fp_line
			(start -0.120396 0.3048)
			(end -0.120396 0.2794)
			(stroke
				(width 0.1)
				(type default)
			)
			(layer "B.Fab")
		)
		(fp_line
			(start 0.12065 -0.305054)
			(end 0.12065 -0.2794)
			(stroke
				(width 0.1)
				(type default)
			)
			(layer "B.Fab")
		)
		(fp_line
			(start 0.12065 -0.2794)
			(end -0.12065 -0.2794)
			(stroke
				(width 0.1)
				(type default)
			)
			(layer "B.Fab")
		)
		(fp_line
			(start 0.12065 0.2794)
			(end 0.12065 0.3048)
			(stroke
				(width 0.1)
				(type default)
			)
			(layer "B.Fab")
		)
		(fp_line
			(start 0.12065 0.3048)
			(end 0.67945 0.3048)
			(stroke
				(width 0.1)
				(type default)
			)
			(layer "B.Fab")
		)
		(fp_line
			(start 0.67945 -0.305054)
			(end 0.12065 -0.305054)
			(stroke
				(width 0.1)
				(type default)
			)
			(layer "B.Fab")
		)
		(fp_line
			(start 0.67945 0.3048)
			(end 0.67945 -0.305054)
			(stroke
				(width 0.1)
				(type default)
			)
			(layer "B.Fab")
		)
		(pad "1" smd circle
			(at 0.40005 0 180)
			(size 0 0)
			(layers "B.Cu" "B.Mask" "B.Paste")
			(net "PVDDCR_CPU1_P0")
		)
		(pad "2" smd circle
			(at -0.40005 0 180)
			(size 0 0)
			(layers "B.Cu" "B.Mask" "B.Paste")
			(net "GND")
		)
	)
)
